FILE_TYPE = CONNECTIVITY;
{Allegro Design Entry HDL 17.4-2019 S026 (4007227) 1/17/2022}
"PAGE_NUMBER" = 428;
0"NC";
1"P5E_CPU0_P3_RX_BUF_DP<15:8>";
2"P5E_CPU0_P3_RX_BUF_DN<7:0>";
3"P5E_CPU0_P3_RX_BUF_DP<7:0>";
4"P5E_CPU0_P3_RX_BUF_DN<15:8>";
5"P5E_CPU0_P3_RX_BUF_DP<9>";
6"P5E_CPU0_P3_RX_BUF_DP<6>";
7"P5E_CPU0_P3_RX_BUF_DN<6>";
8"P5E_CPU0_P3_RX_BUF_DP<3>";
9"P5E_CPU0_P3_RX_BUF_DP<5>";
10"P5E_CPU0_P3_RX_BUF_DP<7>";
11"P5E_CPU0_P3_RX_BUF_DP<11>";
12"P5E_CPU0_P3_RX_BUF_DP<10>";
13"P5E_CPU0_P3_RX_BUF_DP<12>";
14"P5E_CPU0_P3_RX_BUF_DN<8>";
15"P5E_CPU0_P3_RX_BUF_DN<12>";
16"P5E_CPU0_P3_RX_BUF_DP<13>";
17"P5E_CPU0_P3_RX_BUF_DP<8>";
18"P5E_CPU0_P3_RX_BUF_DN<9>";
19"P5E_CPU0_P3_RX_BUF_DN<10>";
20"P5E_CPU0_P3_RX_BUF_DN<11>";
21"P5E_CPU0_P3_RX_BUF_DN<13>";
22"P5E_CPU0_P3_RX_BUF_DP<14>";
23"P5E_CPU0_P3_RX_BUF_DP<0>";
24"P5E_CPU0_P3_RX_BUF_DN<0>";
25"P5E_CPU0_P3_RX_BUF_DN<4>";
26"P5E_CPU0_P3_RX_BUF_DN<15>";
27"P5E_CPU0_P3_RX_BUF_DN<14>";
28"P5E_CPU0_P3_RX_BUF_DP<4>";
29"P5E_CPU0_P3_RX_BUF_DN<5>";
30"P5E_CPU0_P3_RX_BUF_DN<7>";
31"P5E_CPU0_P3_RX_BUF_DN<3>";
32"P5E_CPU0_P3_RX_BUF_DP<2>";
33"P5E_CPU0_P3_RX_BUF_DN<2>";
34"P5E_CPU0_P3_RX_BUF_DP<1>";
35"P5E_CPU0_P3_RX_BUF_DN<1>";
36"P5E_CPU0_P3_RX_BUF_DP<15>";
%"PT5161LRS"
"1","(-7700,3775)","0","pure_quanta","I1";
;
LOCATION"U6013"
$SEC"1"
CDS_SEC"1"
PART_TYPE"SMLF"
MATERIAL"IC"
VALUE"PT5161LRS"
CDS_LIB"pure_quanta"
CDS_LMAN_SYM_OUTLINE"-350,1450,300,-1400"
NEEDS_NO_SIZE"TRUE"
PART_NUMBER"AJ051610U03";
"A_PERN7"
$PN"CB2"14;
"A_PERP7"
$PN"CD1"17;
"A_PERN6"
$PN"BR2"18;
"A_PERP6"
$PN"BU1"5;
"A_PERN5"
$PN"BH2"19;
"A_PERP5"
$PN"BK1"12;
"A_PERN4"
$PN"BA2"20;
"A_PERP4"
$PN"BC1"11;
"A_PERN3"
$PN"AP2"15;
"A_PERP3"
$PN"AT1"13;
"A_PERN2"
$PN"AG2"21;
"A_PERP2"
$PN"AJ1"16;
"A_PERN1"
$PN"Y2"27;
"A_PERP1"
$PN"AB1"22;
"A_PERN0"
$PN"N2"26;
"A_PERP0"
$PN"R1"36;
%"TAP"
"1","(-6675,3975)","0","standard","I10";
;
CDS_LIB"standard"
BODY_TYPE"PLUMBING"
HDL_TAP"TRUE";
"B \NAC \NWC"1;
"S \NAC"
BN"12"13;
%"TAP"
"1","(-6475,3875)","0","standard","I11";
;
CDS_LIB"standard"
BODY_TYPE"PLUMBING"
HDL_TAP"TRUE";
"B \NAC \NWC"4;
"S \NAC"
BN"12"15;
%"TAP"
"1","(-6675,4325)","0","standard","I12";
;
CDS_LIB"standard"
BODY_TYPE"PLUMBING"
HDL_TAP"TRUE";
"B \NAC \NWC"1;
"S \NAC"
BN"13"16;
%"TAP"
"1","(-6475,4225)","0","standard","I13";
;
CDS_LIB"standard"
BODY_TYPE"PLUMBING"
HDL_TAP"TRUE";
"B \NAC \NWC"4;
"S \NAC"
BN"13"21;
%"TAP"
"1","(-6475,4575)","0","standard","I14";
;
CDS_LIB"standard"
BODY_TYPE"PLUMBING"
HDL_TAP"TRUE";
"B \NAC \NWC"4;
"S \NAC"
BN"14"27;
%"TAP"
"1","(-6675,4675)","0","standard","I15";
;
CDS_LIB"standard"
BODY_TYPE"PLUMBING"
HDL_TAP"TRUE";
"B \NAC \NWC"1;
"S \NAC"
BN"14"22;
%"TAP"
"1","(-6675,5025)","0","standard","I16";
;
CDS_LIB"standard"
BODY_TYPE"PLUMBING"
HDL_TAP"TRUE";
"B \NAC \NWC"1;
"S \NAC"
BN"15"36;
%"TAP"
"1","(-6475,4925)","0","standard","I17";
;
CDS_LIB"standard"
BODY_TYPE"PLUMBING"
HDL_TAP"TRUE";
"B \NAC \NWC"4;
"S \NAC"
BN"15"26;
%"TAP"
"1","(-6475,2475)","0","standard","I2";
;
CDS_LIB"standard"
BODY_TYPE"PLUMBING"
HDL_TAP"TRUE";
"B \NAC \NWC"4;
"S \NAC"
BN"8"14;
%"TAP"
"1","(-2225,2600)","0","standard","I20";
;
CDS_LIB"standard"
BODY_TYPE"PLUMBING"
HDL_TAP"TRUE";
"B \NAC \NWC"3;
"S \NAC"
BN"0"23;
%"TAP"
"1","(-2225,2950)","0","standard","I21";
;
CDS_LIB"standard"
BODY_TYPE"PLUMBING"
HDL_TAP"TRUE";
"B \NAC \NWC"3;
"S \NAC"
BN"1"34;
%"TAP"
"1","(-2225,3300)","0","standard","I22";
;
CDS_LIB"standard"
BODY_TYPE"PLUMBING"
HDL_TAP"TRUE";
"B \NAC \NWC"3;
"S \NAC"
BN"2"32;
%"TAP"
"1","(-2225,3650)","0","standard","I23";
;
CDS_LIB"standard"
BODY_TYPE"PLUMBING"
HDL_TAP"TRUE";
"B \NAC \NWC"3;
"S \NAC"
BN"3"8;
%"TAP"
"1","(-2225,4000)","0","standard","I24";
;
CDS_LIB"standard"
BODY_TYPE"PLUMBING"
HDL_TAP"TRUE";
"B \NAC \NWC"3;
"S \NAC"
BN"4"28;
%"TAP"
"1","(-2025,2500)","0","standard","I25";
;
CDS_LIB"standard"
BODY_TYPE"PLUMBING"
HDL_TAP"TRUE";
"B \NAC \NWC"2;
"S \NAC"
BN"0"24;
%"TAP"
"1","(-2025,2850)","0","standard","I26";
;
CDS_LIB"standard"
BODY_TYPE"PLUMBING"
HDL_TAP"TRUE";
"B \NAC \NWC"2;
"S \NAC"
BN"1"35;
%"TAP"
"1","(-2025,3200)","0","standard","I27";
;
CDS_LIB"standard"
BODY_TYPE"PLUMBING"
HDL_TAP"TRUE";
"B \NAC \NWC"2;
"S \NAC"
BN"2"33;
%"TAP"
"1","(-2025,3550)","0","standard","I28";
;
CDS_LIB"standard"
BODY_TYPE"PLUMBING"
HDL_TAP"TRUE";
"B \NAC \NWC"2;
"S \NAC"
BN"3"31;
%"TAP"
"1","(-2025,3900)","0","standard","I29";
;
CDS_LIB"standard"
BODY_TYPE"PLUMBING"
HDL_TAP"TRUE";
"B \NAC \NWC"2;
"S \NAC"
BN"4"25;
%"TAP"
"1","(-6675,2575)","0","standard","I3";
;
CDS_LIB"standard"
BODY_TYPE"PLUMBING"
HDL_TAP"TRUE";
"B \NAC \NWC"1;
"S \NAC"
BN"8"17;
%"TAP"
"1","(-2225,4350)","0","standard","I30";
;
CDS_LIB"standard"
BODY_TYPE"PLUMBING"
HDL_TAP"TRUE";
"B \NAC \NWC"3;
"S \NAC"
BN"5"9;
%"TAP"
"1","(-2225,4700)","0","standard","I31";
;
CDS_LIB"standard"
BODY_TYPE"PLUMBING"
HDL_TAP"TRUE";
"B \NAC \NWC"3;
"S \NAC"
BN"6"6;
%"TAP"
"1","(-2225,5050)","0","standard","I32";
;
CDS_LIB"standard"
BODY_TYPE"PLUMBING"
HDL_TAP"TRUE";
"B \NAC \NWC"3;
"S \NAC"
BN"7"10;
%"TAP"
"1","(-2025,4250)","0","standard","I33";
;
CDS_LIB"standard"
BODY_TYPE"PLUMBING"
HDL_TAP"TRUE";
"B \NAC \NWC"2;
"S \NAC"
BN"5"29;
%"TAP"
"1","(-2025,4600)","0","standard","I34";
;
CDS_LIB"standard"
BODY_TYPE"PLUMBING"
HDL_TAP"TRUE";
"B \NAC \NWC"2;
"S \NAC"
BN"6"7;
%"TAP"
"1","(-2025,4950)","0","standard","I35";
;
CDS_LIB"standard"
BODY_TYPE"PLUMBING"
HDL_TAP"TRUE";
"B \NAC \NWC"2;
"S \NAC"
BN"7"30;
%"PT5161LRS"
"2","(-3250,3800)","0","pure_quanta","I38";
;
LOCATION"U6013"
$SEC"2"
CDS_SEC"2"
VALUE"PT5161LRS"
MATERIAL"IC"
PART_TYPE"SMLF"
NEEDS_NO_SIZE"TRUE"
CDS_LMAN_SYM_OUTLINE"-350,1450,300,-1400"
CDS_LIB"pure_quanta"
PART_NUMBER"AJ051610U03";
"A_PERN15"
$PN"EV2"24;
"A_PERP15"
$PN"EY1"23;
"A_PERN14"
$PN"EL2"35;
"A_PERP14"
$PN"EN1"34;
"A_PERN13"
$PN"ED2"33;
"A_PERP13"
$PN"EF1"32;
"A_PERN12"
$PN"DU2"31;
"A_PERP12"
$PN"DW1"8;
"A_PERN11"
$PN"DK2"25;
"A_PERP11"
$PN"DM1"28;
"A_PERN10"
$PN"DC2"29;
"A_PERP10"
$PN"DE1"9;
"A_PERN9"
$PN"CT2"7;
"A_PERP9"
$PN"CV1"6;
"A_PERN8"
$PN"CJ2"30;
"A_PERP8"
$PN"CL1"10;
%"TAP"
"1","(-6675,2925)","0","standard","I4";
;
CDS_LIB"standard"
BODY_TYPE"PLUMBING"
HDL_TAP"TRUE";
"B \NAC \NWC"1;
"S \NAC"
BN"9"5;
%"TAP"
"1","(-6475,2825)","0","standard","I5";
;
CDS_LIB"standard"
BODY_TYPE"PLUMBING"
HDL_TAP"TRUE";
"B \NAC \NWC"4;
"S \NAC"
BN"9"18;
%"TAP"
"1","(-6675,3275)","0","standard","I6";
;
CDS_LIB"standard"
BODY_TYPE"PLUMBING"
HDL_TAP"TRUE";
"B \NAC \NWC"1;
"S \NAC"
BN"10"12;
%"TAP"
"1","(-6475,3175)","0","standard","I7";
;
CDS_LIB"standard"
BODY_TYPE"PLUMBING"
HDL_TAP"TRUE";
"B \NAC \NWC"4;
"S \NAC"
BN"10"19;
%"TAP"
"1","(-6475,3525)","0","standard","I8";
;
CDS_LIB"standard"
BODY_TYPE"PLUMBING"
HDL_TAP"TRUE";
"B \NAC \NWC"4;
"S \NAC"
BN"11"20;
%"TAP"
"1","(-6675,3625)","0","standard","I9";
;
CDS_LIB"standard"
BODY_TYPE"PLUMBING"
HDL_TAP"TRUE";
"B \NAC \NWC"1;
"S \NAC"
BN"11"11;
END.
